FILE_TYPE = CONNECTIVITY;
{Allegro Design Entry HDL 17.2-2016 S081 (4005846) 1/11/2022}
"PAGE_NUMBER" = 178;
0"NC";
1"P3V3_AUX\g";
2"P3V3_AUX\g";
3"P1V8_PCH_AUX\g";
4"P1V8_PCH_PLL_AUX\g";
5"P1V05_PCH_AUX\g";
6"P1V05_PCH_AUX\g";
7"P1V05_PCH_PLL_AUX\g";
8"P3V3_RTC_AUX\g";
9"GND\g";
10"TP_PCH_RSVD<16>"CDS_PHYS_NET_NAME"FM_PCH_SLP_S4_N";
11"TP_PCH_RSVD<15>"CDS_PHYS_NET_NAME"FM_PCH_SLP_S4_N";
%"UNIVERSAL_POWER"
"1","(5300,1625)","0","logical_power","I10";
;
HDL_POWER"P3V3_RTC_AUX"
CDS_LIB"logical_power";
"A"8;
%"EMMITSBURG_REV0P9"
"8","(1875,2250)","0","pure_quanta","I11";
;
PART_NUMBER"AJ0QV2N0T00"
PART_TYPE"SMLF"
VALUE"GFNOCPU04302300-QV2N-MM#99A1WT"
MATERIAL"IC"
$LOCATION"U4"
CDS_LIB"pure_quanta"
CDS_LMAN_SYM_OUTLINE"-1500,1225,1500,-1225"
NEEDS_NO_SIZE"TRUE"
CDS_LOCATION"U4"
$SEC"8"
CDS_SEC"8";
"VSS_BG40"
$PN"BG40"9;
"VCCRTC"
$PN"AH15"8;
"VCCP_VNN_AF20"
$PN"AF20"5;
"VCCP_VNN_AF22"
$PN"AF22"5;
"VCCP_VNN_AG20"
$PN"AG20"5;
"VCCP_VNN_AG22"
$PN"AG22"5;
"VCCP_VNN_AJ20"
$PN"AJ20"5;
"VCCP_VNN_AJ22"
$PN"AJ22"5;
"VCCP_VNN_AL20"
$PN"AL20"5;
"VCCP_VNN_AL22"
$PN"AL22"5;
"VCCP_VNN_AN23"
$PN"AN23"5;
"VCCP_VNN_AP21"
$PN"AP21"5;
"VCCP_VNN_AR23"
$PN"AR23"5;
"VCCP_GPPI_1P8_3P3"
$PN"AD17"2;
"VCCP_GPPE_1P8_3P3"
$PN"AN20"2;
"VCCP_GPPD_1P8_3P3"
$PN"T15"2;
"VCCP_3P3_DSW_V15"
$PN"V15"1;
"VCCP_3P3_DSW_AD15"
$PN"AD15"1;
"VCCP_3P3_AK15"
$PN"AK15"2;
"VCCP_3P3_AF17"
$PN"AF17"2;
"VCCP_3P3_AG17"
$PN"AG17"2;
"VCCP_3P3_AJ17"
$PN"AJ17"2;
"VCCP_3P3_AL17"
$PN"AL17"2;
"VCCP_3P3_P21"
$PN"P21"2;
"VCCP_1P8_FILTERED_AB31"
$PN"AB31"4;
"VCCP_1P8_FILTERED_W27"
$PN"W27"4;
"VCCP_1P8_FILTERED_U29"
$PN"U29"4;
"VCCP_1P8_FILTERED_W29"
$PN"W29"4;
"VCCP_1P8_FILTERED_AB34"
$PN"AB34"4;
"VCCP_1P8_U17"
$PN"U17"3;
"VCCP_1P8_U19"
$PN"U19"3;
"VCCP_1P8_U20"
$PN"U20"3;
"VCCP_1P8_U22"
$PN"U22"3;
"VCCP_1P8_U24"
$PN"U24"3;
"VCCP_1P8_N20"
$PN"N20"3;
"VCCP_1P05_FILTERED_R23"
$PN"R23"7;
"VCCP_1P05_FILTERED_R26"
$PN"R26"7;
"VCCP_1P05_FILTERED_AA29"
$PN"AA29"7;
"VCCP_1P05_FILTERED_U27"
$PN"U27"7;
"VCCP_1P05_FILTERED_R29"
$PN"R29"7;
"VCCP_1P05_FILTERED_AE29"
$PN"AE29"7;
"VCCP_1P05_FILTERED_AG29"
$PN"AG29"7;
"VCCP_1P05_FILTERED_AL25"
$PN"AL25"7;
"VCCP_1P05_P15"
$PN"P15"6;
"VCCP_1P05_M24"
$PN"M24"6;
"VCCP_1P05_AR26"
$PN"AR26"6;
"VCCP_1P05_N23"
$PN"N23"6;
"VCCP_1P05_N26"
$PN"N26"6;
"VCCP_1P05_FILTERED_AB27"
$PN"AB27"7;
"VCCP_1P05_AD25"
$PN"AD25"6;
"VCCP_1P05_AD27"
$PN"AD27"6;
"VCCP_1P05_AF25"
$PN"AF25"6;
"VCCP_1P05_AF27"
$PN"AF27"6;
"VCCP_1P05_AG25"
$PN"AG25"6;
"VCCP_1P05_AG27"
$PN"AG27"6;
"VCCP_1P05_AJ25"
$PN"AJ25"6;
"VCCP_1P05_AJ27"
$PN"AJ27"6;
"VCCP_1P05_AB19"
$PN"AB19"6;
"VCCP_1P05_AB20"
$PN"AB20"6;
"VCCP_1P05_AB22"
$PN"AB22"6;
"VCCP_1P05_AB24"
$PN"AB24"6;
"VCCP_1P05_W17"
$PN"W17"6;
"VCCP_1P05_W19"
$PN"W19"6;
"VCCP_1P05_W20"
$PN"W20"6;
"VCCP_1P05_W22"
$PN"W22"6;
"VCCP_1P05_W24"
$PN"W24"6;
"RSVD_AN26"
$PN"AN26"11;
"RSVD_AF15"
$PN"AF15"10;
%"UNIVERSAL_POWER"
"1","(-600,2150)","0","logical_power","I17";
;
HDL_POWER"P1V05_PCH_PLL_AUX"
CDS_LIB"logical_power";
"A"7;
%"UNIVERSAL_GND"
"1","(-50,825)","0","logical_power","I18";
;
CDS_LIB"logical_power"
HDL_POWER"GND"
ROOM"IO_SLOT";
"A"9;
%"UNIVERSAL_POWER"
"1","(-75,3575)","0","logical_power","I2";
;
HDL_POWER"P1V05_PCH_AUX"
CDS_LIB"logical_power";
"A"6;
%"UNIVERSAL_POWER"
"1","(3775,3600)","0","logical_power","I5";
;
HDL_POWER"P1V05_PCH_AUX"
CDS_LIB"logical_power";
"A"5;
%"UNIVERSAL_POWER"
"1","(4150,2975)","0","logical_power","I6";
;
HDL_POWER"P1V8_PCH_PLL_AUX"
CDS_LIB"logical_power";
"A"4;
%"UNIVERSAL_POWER"
"1","(4450,2675)","0","logical_power","I7";
;
HDL_POWER"P1V8_PCH_AUX"
CDS_LIB"logical_power";
"A"3;
%"UNIVERSAL_POWER"
"1","(4675,2325)","0","logical_power","I8";
;
HDL_POWER"P3V3_AUX"
CDS_LIB"logical_power";
"A"2;
%"UNIVERSAL_POWER"
"1","(5000,1775)","0","logical_power","I9";
;
HDL_POWER"P3V3_AUX"
CDS_LIB"logical_power";
"A"1;
END.
